# S9S_MB_2U (Grand Teton) — schematic netlist excerpt (pin names and nets, part order shuffled) for the footprints in the layout excerpt that follows; sources: Cadence DE-HDL packaged netlist, KiCad conversion of 03242023_DA0F0TMBIJ0_F0T_Motherboard_J_brd_V01_OCP.brd

PR453  Q_RES  10K 1% EMPTY  pkg 0402LF  page 284 : A = PVCCFA_EHV_FIVRA_CPU1_BTSEN ; B = GND
R3216  Q_RES  100 1% CHIP  pkg 0402LF  page 160 : A = OCP_V3_2_ISO_BIF1_EN ; B = GND

(kicad_pcb
	(version 20260206)
	(generator "pcbnew")
	(generator_version "10.0")
	(general
		(thickness 1.6)
		(legacy_teardrops no)
	)
	(paper "A4")
	(title_block
		(title "03242023_DA0F0TMBIJ0_F0T_Motherboard_J_brd_V01_OCP.brd")
		(comment 1 "Grand Teton / footprints 5145-5146 of 6105")
	)
	(layers
		(0 "F.Cu" signal "TOP")
		(4 "In1.Cu" signal "GND")
		(6 "In2.Cu" signal "IN1")
		(8 "In3.Cu" signal "GND1")
		(10 "In4.Cu" signal "IN2")
		(12 "In5.Cu" signal "GND2")
		(14 "In6.Cu" signal "IN3")
		(16 "In7.Cu" signal "GND3")
		(18 "In8.Cu" signal "VCC")
		(20 "In9.Cu" signal "VCC1")
		(22 "In10.Cu" signal "GND4")
		(24 "In11.Cu" signal "IN4")
		(26 "In12.Cu" signal "GND5")
		(28 "In13.Cu" signal "IN5")
		(30 "In14.Cu" signal "GND6")
		(32 "In15.Cu" signal "IN6")
		(34 "In16.Cu" signal "GND7")
		(2 "B.Cu" signal "BOTTOM")
		(9 "F.Adhes" user "F.Adhesive")
		(11 "B.Adhes" user "B.Adhesive")
		(13 "F.Paste" user "Package Geometry/Pastemask Top")
		(15 "B.Paste" user "Package Geometry/Pastemask Bottom")
		(5 "F.SilkS" user "Ref Des/Silkscreen Top")
		(7 "B.SilkS" user "Ref Des/Silkscreen Bottom")
		(1 "F.Mask" user "Board Geometry/Soldermask Top")
		(3 "B.Mask" user "Board Geometry/Soldermask Bottom")
		(17 "Dwgs.User" user "User.Drawings")
		(19 "Cmts.User" user "User.Comments")
		(21 "Eco1.User" user "User.Eco1")
		(23 "Eco2.User" user "User.Eco2")
		(25 "Edge.Cuts" user "Board Geometry/Outline")
		(27 "Margin" user)
		(31 "F.CrtYd" user "Package Geometry/Place Bound Top")
		(29 "B.CrtYd" user "Package Geometry/Place Bound Bottom")
		(35 "F.Fab" user "Ref Des/Assembly Top")
		(33 "B.Fab" user "Ref Des/Assembly Bottom")
	)
	(footprint ""
		(layer "B.Cu")
		(at 62.702186 -15.769844 90)
		(property "Reference" "R3216"
			(at 0 0 90)
			(layer "B.SilkS")
			(hide yes)
			(effects
				(font
					(size 1.27 1.27)
				)
				(justify mirror)
			)
		)
		(property "Value" ""
			(at 0 0 90)
			(layer "B.Fab")
			(effects
				(font
					(size 1.27 1.27)
				)
				(justify mirror)
			)
		)
		(duplicate_pad_numbers_are_jumpers no)
		(fp_line
			(start 0.7874 -0.4064)
			(end -0.7874 -0.4064)
			(stroke
				(width 0.1524)
				(type default)
			)
			(layer "B.SilkS")
		)
		(fp_line
			(start -0.7874 -0.4064)
			(end -0.7874 0.4064)
			(stroke
				(width 0.1524)
				(type default)
			)
			(layer "B.SilkS")
		)
		(fp_line
			(start 0.7874 0.4064)
			(end 0.7874 -0.4064)
			(stroke
				(width 0.1524)
				(type default)
			)
			(layer "B.SilkS")
		)
		(fp_line
			(start -0.7874 0.4064)
			(end 0.7874 0.4064)
			(stroke
				(width 0.1524)
				(type default)
			)
			(layer "B.SilkS")
		)
		(fp_line
			(start 0.67945 -0.305054)
			(end 0.12065 -0.305054)
			(stroke
				(width 0.1)
				(type default)
			)
			(layer "B.Fab")
		)
		(fp_line
			(start 0.12065 -0.305054)
			(end 0.12065 -0.2794)
			(stroke
				(width 0.1)
				(type default)
			)
			(layer "B.Fab")
		)
		(fp_line
			(start -0.12065 -0.3048)
			(end -0.67945 -0.3048)
			(stroke
				(width 0.1)
				(type default)
			)
			(layer "B.Fab")
		)
		(fp_line
			(start -0.67945 -0.3048)
			(end -0.67945 0.3048)
			(stroke
				(width 0.1)
				(type default)
			)
			(layer "B.Fab")
		)
		(fp_line
			(start 0.12065 -0.2794)
			(end -0.12065 -0.2794)
			(stroke
				(width 0.1)
				(type default)
			)
			(layer "B.Fab")
		)
		(fp_line
			(start -0.12065 -0.2794)
			(end -0.12065 -0.3048)
			(stroke
				(width 0.1)
				(type default)
			)
			(layer "B.Fab")
		)
		(fp_line
			(start 0.12065 0.2794)
			(end 0.12065 0.3048)
			(stroke
				(width 0.1)
				(type default)
			)
			(layer "B.Fab")
		)
		(fp_line
			(start -0.120396 0.2794)
			(end 0.12065 0.2794)
			(stroke
				(width 0.1)
				(type default)
			)
			(layer "B.Fab")
		)
		(fp_line
			(start 0.67945 0.3048)
			(end 0.67945 -0.305054)
			(stroke
				(width 0.1)
				(type default)
			)
			(layer "B.Fab")
		)
		(fp_line
			(start 0.12065 0.3048)
			(end 0.67945 0.3048)
			(stroke
				(width 0.1)
				(type default)
			)
			(layer "B.Fab")
		)
		(fp_line
			(start -0.120396 0.3048)
			(end -0.120396 0.2794)
			(stroke
				(width 0.1)
				(type default)
			)
			(layer "B.Fab")
		)
		(fp_line
			(start -0.67945 0.3048)
			(end -0.120396 0.3048)
			(stroke
				(width 0.1)
				(type default)
			)
			(layer "B.Fab")
		)
		(pad "1" smd circle
			(at 0.40005 0 270)
			(size 0 0)
			(layers "B.Cu" "B.Mask" "B.Paste")
			(net "OCP_V3_2_ISO_BIF1_EN")
		)
		(pad "2" smd circle
			(at -0.40005 0 270)
			(size 0 0)
			(layers "B.Cu" "B.Mask" "B.Paste")
			(net "GND")
		)
	)
	(footprint ""
		(layer "B.Cu")
		(at 111.490506 -358.522016)
		(property "Reference" "PR453"
			(at 0 0 0)
			(layer "B.SilkS")
			(hide yes)
			(effects
				(font
					(size 1.27 1.27)
				)
				(justify mirror)
			)
		)
		(property "Value" ""
			(at 0 0 0)
			(layer "B.Fab")
			(effects
				(font
					(size 1.27 1.27)
				)
				(justify mirror)
			)
		)
		(duplicate_pad_numbers_are_jumpers no)
		(fp_line
			(start -0.7874 -0.4064)
			(end -0.7874 0.4064)
			(stroke
				(width 0.1524)
				(type default)
			)
			(layer "B.SilkS")
		)
		(fp_line
			(start -0.7874 0.4064)
			(end 0.7874 0.4064)
			(stroke
				(width 0.1524)
				(type default)
			)
			(layer "B.SilkS")
		)
		(fp_line
			(start 0.7874 -0.4064)
			(end -0.7874 -0.4064)
			(stroke
				(width 0.1524)
				(type default)
			)
			(layer "B.SilkS")
		)
		(fp_line
			(start 0.7874 0.4064)
			(end 0.7874 -0.4064)
			(stroke
				(width 0.1524)
				(type default)
			)
			(layer "B.SilkS")
		)
		(fp_line
			(start -0.67945 -0.3048)
			(end -0.67945 0.3048)
			(stroke
				(width 0.1)
				(type default)
			)
			(layer "B.Fab")
		)
		(fp_line
			(start -0.67945 0.3048)
			(end -0.120396 0.3048)
			(stroke
				(width 0.1)
				(type default)
			)
			(layer "B.Fab")
		)
		(fp_line
			(start -0.12065 -0.3048)
			(end -0.67945 -0.3048)
			(stroke
				(width 0.1)
				(type default)
			)
			(layer "B.Fab")
		)
		(fp_line
			(start -0.12065 -0.2794)
			(end -0.12065 -0.3048)
			(stroke
				(width 0.1)
				(type default)
			)
			(layer "B.Fab")
		)
		(fp_line
			(start -0.120396 0.2794)
			(end 0.12065 0.2794)
			(stroke
				(width 0.1)
				(type default)
			)
			(layer "B.Fab")
		)
		(fp_line
			(start -0.120396 0.3048)
			(end -0.120396 0.2794)
			(stroke
				(width 0.1)
				(type default)
			)
			(layer "B.Fab")
		)
		(fp_line
			(start 0.12065 -0.305054)
			(end 0.12065 -0.2794)
			(stroke
				(width 0.1)
				(type default)
			)
			(layer "B.Fab")
		)
		(fp_line
			(start 0.12065 -0.2794)
			(end -0.12065 -0.2794)
			(stroke
				(width 0.1)
				(type default)
			)
			(layer "B.Fab")
		)
		(fp_line
			(start 0.12065 0.2794)
			(end 0.12065 0.3048)
			(stroke
				(width 0.1)
				(type default)
			)
			(layer "B.Fab")
		)
		(fp_line
			(start 0.12065 0.3048)
			(end 0.67945 0.3048)
			(stroke
				(width 0.1)
				(type default)
			)
			(layer "B.Fab")
		)
		(fp_line
			(start 0.67945 -0.305054)
			(end 0.12065 -0.305054)
			(stroke
				(width 0.1)
				(type default)
			)
			(layer "B.Fab")
		)
		(fp_line
			(start 0.67945 0.3048)
			(end 0.67945 -0.305054)
			(stroke
				(width 0.1)
				(type default)
			)
			(layer "B.Fab")
		)
		(pad "1" smd circle
			(at 0.40005 0 180)
			(size 0 0)
			(layers "B.Cu" "B.Mask" "B.Paste")
			(net "PVCCFA_EHV_FIVRA_CPU1_BTSEN")
		)
		(pad "2" smd circle
			(at -0.40005 0 180)
			(size 0 0)
			(layers "B.Cu" "B.Mask" "B.Paste")
			(net "GND")
		)
	)
)
